FILE_TYPE = CONNECTIVITY;
{Allegro Design Entry HDL 17.2-2016 S081 (4005846) 1/11/2022}
"PAGE_NUMBER" = 153;
0"NC";
1"P3V3_AUX\g";
2"P3V3_AUX\g";
3"P12V_AUX\g";
4"P3V3_AUX\g";
5"P3V3_AUX\g";
6"P12V_AUX\g";
7"P3V3_AUX\g";
8"P12V_AUX\g";
9"P3V3_AUX\g";
10"P3V3_AUX\g";
11"P12V_OCP_SFF\g";
12"P3V3_AUX\g";
13"P3V3_OCP_SFF_R\g";
14"GND\g";
15"GND\g";
16"GND\g";
17"GND\g";
18"GND\g";
19"GND\g";
20"GND\g";
21"GND\g";
22"GND\g";
23"GND\g";
24"GND\g";
25"GND\g";
26"GND\g";
27"GND\g";
28"GND\g";
29"GND\g";
30"GND\g";
31"GND\g";
32"GND\g";
33"GND\g";
34"GND\g";
35"GND\g";
36"GND\g";
37"P3V3_OCP_UV_1";
38"P3V3_OCP_VCC_1";
39"HP_LVC3_OCP_V3_1_PRSNT2_N_R"CDS_PHYS_NET_NAME"HP_LVC3_OCP_V3_1_PRSNT2_N_R";
40"HP_LVC3_OCP_V3_1_PRSNT2_N"CDS_PHYS_NET_NAME"HP_LVC3_OCP_V3_1_PRSNT2_N";
41"HP_LVC3_OCP_V3_1_PRSNT2_PLD_N"CDS_PHYS_NET_NAME"HP_LVC3_OCP_V3_1_PRSNT2_PLD_N";
42"P12V_OCP_OV_1";
43"OCP_V3_1_P3V3_PWRGD";
44"P3V3_OCP_FAULT_1";
45"P3V3_OCP_PWRGD_1";
46"P3V3_OCP_GATE_PU202_1";
47"P3V3_OCP_SENSE_1";
48"P12V_OCP_SFF_ISENSE_MAM_TIC";
49"P12V_OCP_SFF_ISENSE_MAM_MAM";
50"HP_LVC3_OCP_V3_1_P12V_PWRGD";
51"P12V_OCP_SENSE_1";
52"P12V_OCP_GATE_1";
53"P12V_OCP_PWRGD_1";
54"P12V_OCP_FAULT_1";
55"P3V3_OCP_REG_1";
56"P3V3_OCP_CB_1";
57"P3V3_OCP_OV_1";
58"P3V3_OCP_UV_1_R1";
59"P12V_OCP_REG_1";
60"P12V_OCP_VCC_1";
61"P12V_OCP_CB_1";
62"HP_LVC3_OCP_V3_1_ATTN_OUT_SW_N"CDS_PHYS_NET_NAME"HP_LVC3_OCP_V3_1_ATTN_OUT_SW_N";
63"P12V_OCP_UV_1";
64"P3V3_OCP_1_EN_G";
65"P12V_OCP_UV_1_R";
66"OCP_SFF_PRSNT3_R_N"CDS_PHYS_NET_NAME"OCP_SFF_PRSNT3_R_N";
67"OCP_SFF_PRSNT1_R_N"CDS_PHYS_NET_NAME"OCP_SFF_PRSNT1_R_N";
68"P3V3_OCP_EN_1_R";
69"P12V_OCP_1_EN_G";
70"HP_LVC3_OCP_V3_1_EN";
71"OCP_SFF_PRSNT0_R_N"CDS_PHYS_NET_NAME"OCP_SFF_PRSNT0_R_N";
72"OCP_SFF_PRSNT2_R_N"CDS_PHYS_NET_NAME"OCP_SFF_PRSNT2_R_N";
73"P12V_OCP_EN_1_R";
%"UNIVERSAL_GND"
"1","(5850,8150)","0","logical_power","I1";
;
HDL_POWER"GND"
CDS_LIB"logical_power";
"A"14;
%"GND"
"1","(3375,9900)","0","logical_power","I10";
;
HDL_POWER"GND"
CDS_LIB"logical_power"
SIZE"1B";
"A<SIZE-1..0>\NAC"16;
%"Q_CAP"
"1","(8575,13125)","0","pure_quanta","I101";
;
PART_NUMBER"CH31006KB18"
VALUE"0.01UF"
VOLTAGE"50V"
PACK_TYPE"C0402"
MATERIAL"EMPTY"
LOCATION"PC2144"
CDS_LIB"pure_quanta"
TOLERANCE"10%"
$SEC"1"
CDS_SEC"1";
"B"
$PN"2"46;
"A"
$PN"1"13;
%"Q_RES"
"2","(8600,12450)","0","pure_quanta","I102";
;
PART_NUMBER"CS24532FB03"
PACK_TYPE"0402LF"
MATERIAL"CHIP"
WATTAGE"1/16W"
TOLERANCE"1%"
ROOM"NIC1_P3V3_BOM1"
VALUE"4.53K"
$LOCATION"PR5481"
CDS_LIB"pure_quanta"
CDS_LOCATION"PR5481"
$SEC"1"
CDS_SEC"1";
"A"
$PN"1"47;
"B"
$PN"2"32;
%"Q_RES"
"2","(8825,13125)","0","pure_quanta","I103";
;
PART_NUMBER"CS61002FB02"
TOLERANCE"1%"
MATERIAL"CHIP"
ROOM"NIC1_P3V3_BOM1"
WATTAGE"1/16W"
PACK_TYPE"0402LF"
VALUE"10M"
LOCATION"PR4525"
CDS_LIB"pure_quanta"
$SEC"1"
CDS_SEC"1";
"A"
$PN"1"13;
"B"
$PN"2"46;
%"SCHOTTKY_AC"
"1","(8950,13700)","1","pure_quanta","I104";
;
PART_NUMBER"BC000340Z30"
MATERIAL"IC"
VALUE"B340A-13-F"
LOCATION"PD103"
CDS_LMAN_SYM_OUTLINE"-75,50,75,-50"
CDS_LIB"pure_quanta"
PART_TYPE"SMLF"
NEEDS_NO_SIZE"TRUE"
$SEC"1"
CDS_SEC"1";
"C"
$PN"C"13;
"A"
$PN"A"36;
%"Q_RES"
"1","(9225,12800)","0","pure_quanta","I105";
;
PART_NUMBER"CS00002JB13"
TOLERANCE"5%"
VALUE"0"
MATERIAL"CHIP"
WATTAGE"1/16W"
ROOM"NIC1_P3V3_BOM1"
PACK_TYPE"0402LF"
$LOCATION"R3794"
CDS_LIB"pure_quanta"
CDS_LOCATION"R3794"
$SEC"1"
CDS_SEC"1";
"B"
$PN"2"43;
"A"
$PN"1"45;
%"GND"
"1","(9300,12825)","0","logical_power","I106";
;
CDS_LIB"logical_power"
HDL_POWER"GND"
SIZE"1B";
"A<SIZE-1..0>\NAC"35;
%"Q_CAP"
"1","(9175,12900)","1","pure_quanta","I107";
;
PART_NUMBER"CH2686K1B01"
ROOM"NIC1_P3V3_BOM1"
VOLTAGE"50V"
PACK_TYPE"C0402"
VALUE"6800PF"
LOCATION"PC2089"
CDS_LIB"pure_quanta"
MATERIAL"X7R"
TOLERANCE"10%"
$SEC"1"
CDS_SEC"1";
"B"
$PN"2"35;
"A"
$PN"1"46;
%"Q_RES"
"2","(9575,13075)","0","pure_quanta","I108";
;
PART_NUMBER"CS41002FB09"
ROOM"NIC1_P3V3_BOM1"
PACK_TYPE"0402LF"
MATERIAL"CHIP"
VALUE"100K"
WATTAGE"1/16W"
TOLERANCE"1%"
LOCATION"R3796"
CDS_LIB"pure_quanta"
$SEC"1"
CDS_SEC"1";
"A"
$PN"1"12;
"B"
$PN"2"44;
%"VCCAUX15"
"1","(9775,13350)","0","logical_power","I109";
;
HDL_POWER"P3V3_AUX"
CDS_LIB"logical_power";
"A"12;
%"Q_RES"
"2","(9950,13075)","0","pure_quanta","I110";
;
PART_NUMBER"CS41002FB09"
PACK_TYPE"0402LF"
MATERIAL"CHIP"
ROOM"NIC1_P3V3_BOM1"
VALUE"100K"
TOLERANCE"1%"
WATTAGE"1/16W"
LOCATION"R3783"
CDS_LIB"pure_quanta"
$SEC"1"
CDS_SEC"1";
"A"
$PN"1"12;
"B"
$PN"2"43;
%"Q_CAP"
"1","(9450,13675)","0","pure_quanta","I111";
;
PART_NUMBER"CH4104K1B00"
PACK_TYPE"0402"
VALUE"0.1UF"
VOLTAGE"25V"
MATERIAL"X7R"
LOCATION"PC2091"
CDS_LIB"pure_quanta"
TOLERANCE"10%"
$SEC"1"
CDS_SEC"1";
"B"
$PN"2"36;
"A"
$PN"1"13;
%"GND"
"1","(10025,13375)","0","logical_power","I112";
;
HDL_POWER"GND"
SIZE"1B"
CDS_LIB"logical_power";
"A<SIZE-1..0>\NAC"36;
%"Q_CAP"
"1","(10025,13675)","0","pure_quanta","I113";
;
PART_NUMBER"CH6103KEA01"
VOLTAGE"16V"
MATERIAL"X6S"
VALUE"10UF"
PACK_TYPE"C0805"
LOCATION"PC2081"
CDS_LIB"pure_quanta"
TOLERANCE"10%"
$SEC"1"
CDS_SEC"1";
"B"
$PN"2"36;
"A"
$PN"1"13;
%"UNIVERSAL_POWER"
"1","(10025,13975)","2","logical_power","I114";
;
HDL_POWER"P3V3_OCP_SFF_R"
CDS_LIB"logical_power";
"A"13;
%"Q_RES"
"2","(3800,9725)","0","pure_quanta","I13";
;
PART_NUMBER"CS21002FB06"
PACK_TYPE"0402LF"
VALUE"1K"
TOLERANCE"1%"
WATTAGE"1/16W"
MATERIAL"CHIP"
LOCATION"R1905"
CDS_LIB"pure_quanta"
$SEC"1"
CDS_SEC"1";
"A"
$PN"1"2;
"B"
$PN"2"71;
%"UNIVERSAL_POWER"
"1","(3800,10025)","0","logical_power","I14";
;
HDL_POWER"P3V3_AUX"
CDS_LIB"logical_power";
"A"2;
%"Q_RES"
"2","(3375,10850)","0","pure_quanta","I15";
;
PART_NUMBER"CS31002FB08"
WATTAGE"1/16W"
PACK_TYPE"0402LF"
ROOM"NIC1_P12V_MAM_MAM_BOM1"
VALUE"10K"
TOLERANCE"1%"
MATERIAL"EMPTY"
$LOCATION"R4068"
ROOM1"NIC1_P12V_MAM_TIC_BOM2"
CDS_LIB"pure_quanta"
CDS_LOCATION"R4068"
$SEC"1"
CDS_SEC"1";
"A"
$PN"1"3;
"B"
$PN"2"69;
%"UNIVERSAL_POWER"
"1","(3375,11100)","0","logical_power","I16";
;
HDL_POWER"P12V_AUX"
CDS_LIB"logical_power";
"A"3;
%"MOSFET_NCH_DUAL"
"2","(4075,10575)","0","pure_quanta","I17";
;
PART_NUMBER"BAM138K0003"
VALUE"PJT138K"
ROOM"NIC1_P12V_MAM_MAM_BOM1"
PART_TYPE"SMLF"
MATERIAL"EMPTY"
$LOCATION"Q123"
ROOM1"NIC1_P12V_MAM_TIC_BOM2"
CDS_LIB"pure_quanta"
CDS_LMAN_SYM_OUTLINE"-150,150,150,-150"
NEEDS_NO_SIZE"TRUE"
CDS_LOCATION"Q123"
$SEC"2"
CDS_SEC"2";
"S2"
$PN"4"21;
"G2"
$PN"5"69;
"D2"
$PN"3"65;
%"GND"
"1","(3550,11275)","0","logical_power","I18";
;
HDL_POWER"GND"
SIZE"1B"
CDS_LIB"logical_power";
"A<SIZE-1..0>\NAC"17;
%"Q_RES"
"1","(3175,11850)","0","pure_quanta","I19";
;
PART_NUMBER"CS00002JB13"
MATERIAL"CHIP"
TOLERANCE"5%"
PACK_TYPE"0402LF"
VALUE"0"
WATTAGE"1/16W"
$LOCATION"R5487"
CDS_LIB"pure_quanta"
CDS_LOCATION"R5487"
$SEC"1"
CDS_SEC"1";
"B"
$PN"2"68;
"A"
$PN"1"70;
%"UNIVERSAL_GND"
"1","(4775,8225)","0","logical_power","I2";
;
HDL_POWER"GND"
CDS_LIB"logical_power";
"A"15;
%"Q_RES"
"2","(3550,11525)","0","pure_quanta","I20";
;
PART_NUMBER"CS24702JB10"
WATTAGE"1/16W"
MATERIAL"CHIP"
PACK_TYPE"0402LF"
TOLERANCE"5%"
VALUE"4.7K"
$LOCATION"R4069"
CDS_LIB"pure_quanta"
CDS_LOCATION"R4069"
$SEC"1"
CDS_SEC"1";
"A"
$PN"1"68;
"B"
$PN"2"17;
%"MOSFET_NCH_DUAL"
"1","(4075,11900)","0","pure_quanta","I21";
;
PART_NUMBER"BAM138K0003"
ROOM"NIC1_P3V3_BOM1"
MATERIAL"IC"
PART_TYPE"SMLF"
VALUE"PJT138K"
$LOCATION"Q124"
CDS_LIB"pure_quanta"
CDS_LMAN_SYM_OUTLINE"-150,150,150,-150"
NEEDS_NO_SIZE"TRUE"
CDS_LOCATION"Q124"
$SEC"1"
CDS_SEC"1";
"D1"
$PN"6"64;
"G1"
$PN"2"68;
"S1"
$PN"1"22;
%"Q_RES"
"2","(4025,8825)","0","pure_quanta","I22";
;
PART_NUMBER"CS21002FB06"
WATTAGE"1/16W"
VALUE"1K"
TOLERANCE"1%"
MATERIAL"CHIP"
PACK_TYPE"0402LF"
LOCATION"R1908"
CDS_LIB"pure_quanta"
$SEC"1"
CDS_SEC"1";
"A"
$PN"1"1;
"B"
$PN"2"66;
%"74LVC2G07DW7"
"1","(5175,8525)","0","pure_quanta","I23";
;
PART_NUMBER"AL002G07003"
VALUE"74LVC2G07DW-7"
PART_TYPE"SMLF"
MATERIAL"IC"
$LOCATION"U212"
NEEDS_NO_SIZE"TRUE"
CDS_LMAN_SYM_OUTLINE"-175,100,175,-100"
CDS_LIB"pure_quanta"
CDS_LOCATION"U212"
$SEC"1"
CDS_SEC"1";
"VCC"
$PN"5"4;
"GND"
$PN"2"15;
"2Y"
$PN"4"39;
"1Y"
$PN"6"39;
"2A"
$PN"3"66;
"1A"
$PN"1"72;
%"UNIVERSAL_GND"
"1","(4775,9150)","0","logical_power","I24";
;
HDL_POWER"GND"
CDS_LIB"logical_power";
"A"18;
%"Q_RES"
"2","(4025,9725)","0","pure_quanta","I25";
;
PART_NUMBER"CS21002FB06"
MATERIAL"CHIP"
TOLERANCE"1%"
VALUE"1K"
PACK_TYPE"0402LF"
WATTAGE"1/16W"
LOCATION"R1907"
CDS_LIB"pure_quanta"
$SEC"1"
CDS_SEC"1";
"A"
$PN"1"2;
"B"
$PN"2"67;
%"74LVC2G07DW7"
"1","(5175,9425)","0","pure_quanta","I26";
;
PART_NUMBER"AL002G07003"
VALUE"74LVC2G07DW-7"
PART_TYPE"SMLF"
MATERIAL"IC"
$LOCATION"U211"
NEEDS_NO_SIZE"TRUE"
CDS_LMAN_SYM_OUTLINE"-175,100,175,-100"
CDS_LIB"pure_quanta"
CDS_LOCATION"U211"
$SEC"1"
CDS_SEC"1";
"VCC"
$PN"5"5;
"GND"
$PN"2"18;
"2Y"
$PN"4"39;
"1Y"
$PN"6"39;
"2A"
$PN"3"67;
"1A"
$PN"1"71;
%"Q_CAP"
"1","(5850,8350)","0","pure_quanta","I27";
;
PART_NUMBER"CH4104K1B00"
VALUE"0.1UF"
MATERIAL"X7R"
VOLTAGE"25V"
TOLERANCE"10%"
PACK_TYPE"0402"
$LOCATION"C593"
CDS_LIB"pure_quanta"
CDS_LOCATION"C593"
$SEC"1"
CDS_SEC"1";
"B"
$PN"2"14;
"A"
$PN"1"4;
%"UNIVERSAL_POWER"
"1","(5850,8625)","0","logical_power","I28";
;
HDL_POWER"P3V3_AUX"
CDS_LIB"logical_power";
"A"4;
%"UNIVERSAL_GND"
"1","(5850,9050)","0","logical_power","I29";
;
HDL_POWER"GND"
CDS_LIB"logical_power";
"A"19;
%"Q_CAP"
"1","(5850,9250)","0","pure_quanta","I30";
;
PART_NUMBER"CH4104K1B00"
VALUE"0.1UF"
VOLTAGE"25V"
PACK_TYPE"0402"
TOLERANCE"10%"
MATERIAL"X7R"
$LOCATION"C592"
CDS_LIB"pure_quanta"
CDS_LOCATION"C592"
$SEC"1"
CDS_SEC"1";
"B"
$PN"2"19;
"A"
$PN"1"5;
%"UNIVERSAL_POWER"
"1","(5850,9525)","0","logical_power","I31";
;
HDL_POWER"P3V3_AUX"
CDS_LIB"logical_power";
"A"5;
%"GND"
"1","(5925,9925)","0","logical_power","I32";
;
HDL_POWER"GND"
SIZE"1B"
CDS_LIB"logical_power";
"A<SIZE-1..0>\NAC"20;
%"Q_RES"
"2","(5925,10175)","0","pure_quanta","I33";
;
PART_NUMBER"CS31502FB05"
WATTAGE"1/16W"
ROOM"NIC1_P12V_MAM_MAM_BOM1"
MATERIAL"EMPTY"
PACK_TYPE"0402LF"
TOLERANCE"1%"
VALUE"15K"
LOCATION"PR3788"
ROOM1"NIC1_P12V_MAM_TIC_BOM2"
CDS_LIB"pure_quanta"
$SEC"1"
CDS_SEC"1";
"A"
$PN"1"42;
"B"
$PN"2"20;
%"GND"
"1","(4125,10275)","0","logical_power","I34";
;
HDL_POWER"GND"
CDS_LIB"logical_power"
SIZE"1B";
"A<SIZE-1..0>\NAC"21;
%"GND"
"1","(4125,11550)","0","logical_power","I35";
;
HDL_POWER"GND"
SIZE"1B"
CDS_LIB"logical_power";
"A<SIZE-1..0>\NAC"22;
%"MOSFET_NCH_DUAL"
"2","(4825,12275)","0","pure_quanta","I36";
;
PART_NUMBER"BAM138K0003"
MATERIAL"IC"
VALUE"PJT138K"
ROOM"NIC1_P3V3_BOM1"
PART_TYPE"SMLF"
LOCATION"Q124"
CDS_LIB"pure_quanta"
CDS_LMAN_SYM_OUTLINE"-150,150,150,-150"
NEEDS_NO_SIZE"TRUE"
$SEC"2"
CDS_SEC"2";
"S2"
$PN"4"23;
"G2"
$PN"5"64;
"D2"
$PN"3"58;
%"GND"
"1","(4875,11925)","0","logical_power","I37";
;
SIZE"1B"
HDL_POWER"GND"
CDS_LIB"logical_power";
"A<SIZE-1..0>\NAC"23;
%"DIODE_TVS"
"1","(5200,11425)","1","pure_quanta","I38";
;
PART_NUMBER"BCSMF14AZ01"
VALUE"SMF14A"
MATERIAL"IC"
LOCATION"PD101"
PIN_NAMES_ROTATE"True"
PART_TYPE"SMLF"
CDS_LMAN_SYM_OUTLINE"-100,50,100,-50"
CDS_LIB"pure_quanta"
$SEC"1"
CDS_SEC"1";
"C"
$PN"C"
Pin_Length"Short"6;
"A"
$PN"A"24;
%"Q_RES"
"1","(5400,10875)","0","pure_quanta","I39";
;
PART_NUMBER"CS00002JB13"
MATERIAL"EMPTY"
WATTAGE"1/16W"
TOLERANCE"5%"
VALUE"0"
PACK_TYPE"0402LF"
ROOM"NIC1_P12V_MAM_MAM_BOM1"
$LOCATION"R3784"
CDS_LIB"pure_quanta"
ROOM1"NIC1_P12V_MAM_TIC_BOM2"
CDS_LOCATION"R3784"
$SEC"1"
CDS_SEC"1";
"B"
$PN"2"63;
"A"
$PN"1"65;
%"Q_RES"
"1","(2425,10200)","0","pure_quanta","I4";
;
PART_NUMBER"CS00002JB13"
TOLERANCE"5%"
MATERIAL"EMPTY"
ROOM"NIC1_P12V_MAM_MAM_BOM1"
PACK_TYPE"0402LF"
WATTAGE"1/16W"
VALUE"0"
$LOCATION"R4061"
ROOM1"NIC1_P12V_MAM_TIC_BOM2"
CDS_LIB"pure_quanta"
CDS_LOCATION"R4061"
$SEC"1"
CDS_SEC"1";
"B"
$PN"2"73;
"A"
$PN"1"70;
%"GND"
"1","(5350,11050)","0","logical_power","I40";
;
HDL_POWER"GND"
CDS_LIB"logical_power"
SIZE"1B";
"A<SIZE-1..0>\NAC"24;
%"Q_RES"
"2","(5925,10450)","0","pure_quanta","I41";
;
PART_NUMBER"CS26802FB02"
ROOM"NIC1_P12V_MAM_MAM_BOM1"
WATTAGE"1/16W"
TOLERANCE"1%"
VALUE"6.8K"
MATERIAL"EMPTY"
PACK_TYPE"0402LF"
LOCATION"PR3787"
ROOM1"NIC1_P12V_MAM_TIC_BOM2"
CDS_LIB"pure_quanta"
$SEC"1"
CDS_SEC"1";
"A"
$PN"1"63;
"B"
$PN"2"42;
%"Q_RES"
"2","(5925,11125)","0","pure_quanta","I42";
;
PART_NUMBER"CS41602FB05"
MATERIAL"EMPTY"
PACK_TYPE"0402LF"
WATTAGE"1/16W"
TOLERANCE"1%"
VALUE"160K"
ROOM"NIC1_P12V_MAM_MAM_BOM1"
LOCATION"PR3786"
ROOM1"NIC1_P12V_MAM_TIC_BOM2"
CDS_LIB"pure_quanta"
$SEC"1"
CDS_SEC"1";
"A"
$PN"1"6;
"B"
$PN"2"63;
%"UNIVERSAL_POWER"
"1","(5350,11775)","0","logical_power","I43";
;
HDL_POWER"P12V_AUX"
CDS_LIB"logical_power";
"A"6;
%"Q_CAP"
"1","(5575,11425)","0","pure_quanta","I44";
;
PART_NUMBER"CH5104KEB02"
VOLTAGE"25V"
PACK_TYPE"C0402"
MATERIAL"X6S"
VALUE"1UF"
LOCATION"PC2079"
TOLERANCE"10%"
CDS_LIB"pure_quanta"
$SEC"1"
CDS_SEC"1";
"B"
$PN"2"24;
"A"
$PN"1"6;
%"Q_RES"
"1","(6750,8725)","0","pure_quanta","I45";
;
PART_NUMBER"CS00002JB13"
WATTAGE"1/16W"
MATERIAL"CHIP"
VALUE"0"
PACK_TYPE"0402LF"
TOLERANCE"5%"
$LOCATION"R4752"
CDS_LIB"pure_quanta"
CDS_LOCATION"R4752"
$SEC"1"
CDS_SEC"1";
"B"
$PN"2"41;
"A"
$PN"1"39;
%"Q_RES"
"1","(6750,8875)","0","pure_quanta","I46";
;
PART_NUMBER"CS00002JB13"
MATERIAL"CHIP"
TOLERANCE"5%"
VALUE"0"
WATTAGE"1/16W"
PACK_TYPE"0402LF"
$LOCATION"R1148"
CDS_LIB"pure_quanta"
CDS_LOCATION"R1148"
$SEC"1"
CDS_SEC"1";
"B"
$PN"2"40;
"A"
$PN"1"39;
%"Q_RES"
"1","(6775,9025)","0","pure_quanta","I47";
;
PART_NUMBER"CS00002JB13"
PACK_TYPE"0402LF"
TOLERANCE"5%"
VALUE"0"
MATERIAL"CHIP"
WATTAGE"1/16W"
$LOCATION"R1147"
CDS_LIB"pure_quanta"
CDS_LOCATION"R1147"
$SEC"1"
CDS_SEC"1";
"B"
$PN"2"62;
"A"
$PN"1"39;
%"GND"
"1","(6775,9900)","0","logical_power","I48";
;
HDL_POWER"GND"
SIZE"1B"
CDS_LIB"logical_power";
"A<SIZE-1..0>\NAC"25;
%"Q_RES"
"2","(6775,10200)","0","pure_quanta","I49";
;
PART_NUMBER"CS33012FB03"
ROOM"NIC1_P12V_MAM_MAM_BOM1"
VALUE"30.1K"
WATTAGE"1/16W"
MATERIAL"EMPTY"
PACK_TYPE"0402LF"
TOLERANCE"1%"
$LOCATION"PR5484"
ROOM1"NIC1_P12V_MAM_TIC_BOM2"
CDS_LIB"pure_quanta"
CDS_LOCATION"PR5484"
$SEC"1"
CDS_SEC"1";
"A"
$PN"1"61;
"B"
$PN"2"25;
%"Q_RES"
"2","(8025,9300)","0","pure_quanta","I50";
;
PART_NUMBER"CS31002FB08"
WATTAGE"1/16W"
TOLERANCE"1%"
VALUE"10K"
MATERIAL"CHIP"
PACK_TYPE"0402LF"
$LOCATION"R1149"
CDS_LIB"pure_quanta"
CDS_LOCATION"R1149"
$SEC"1"
CDS_SEC"1";
"A"
$PN"1"7;
"B"
$PN"2"62;
%"MAX15090BEWIT"
"1","(7525,10700)","0","pure_quanta","I51";
;
PART_NUMBER"AL015080B00"
ROOM"NIC1_P12V_MAM_MAM_BOM1"
VALUE"MAX15090BEWI+T"
PART_TYPE"SMLF"
MATERIAL"EMPTY"
LOCATION"PU203"
ROOM1"NIC1_P12V_MAM_TIC_BOM2"
CDS_LIB"pure_quanta"
PIN_NAMES_ROTATE"True"
CDS_LMAN_SYM_OUTLINE"-250,550,250,-550"
$SEC"1"
CDS_SEC"1";
"PG"
$PN"D7"53;
"FAULT# \B"
$PN"C7"54;
"GND_C2"
$PN"C2"31;
"GND_C1"
$PN"C1"31;
"GND_B2"
$PN"B2"31;
"CDLY"
$PN"A7"31;
"GATE"
$PN"A6"52;
"OUT_D6"
$PN"D6"11;
"OUT_D4"
$PN"D4"11;
"OUT_C6"
$PN"C6"11;
"OUT_C4"
$PN"C4"11;
"OUT_B6"
$PN"B6"11;
"OUT_B4"
$PN"B4"11;
"OUT_A4"
$PN"A4"11;
"ISENSE"
$PN"A1"51;
"OV"
$PN"D3"42;
"UV"
$PN"D2"63;
"REG"
$PN"D1"59;
"EN# \B"
$PN"B7"25;
"CB"
$PN"B1"61;
"IN_D5"
$PN"D5"6;
"IN_C5"
$PN"C5"6;
"IN_C3"
$PN"C3"6;
"IN_B5"
$PN"B5"6;
"IN_B3"
$PN"B3"6;
"IN_A5"
$PN"A5"6;
"IN_A3"
$PN"A3"6;
"VCC"
$PN"A2"60;
%"UNIVERSAL_POWER"
"1","(8025,9600)","0","logical_power","I52";
;
HDL_POWER"P3V3_AUX"
CDS_LIB"logical_power";
"A"7;
%"GND"
"1","(6250,10625)","0","logical_power","I53";
;
HDL_POWER"GND"
CDS_LIB"logical_power"
SIZE"1B";
"A<SIZE-1..0>\NAC"26;
%"Q_CAP"
"1","(6475,10700)","1","pure_quanta","I54";
;
PART_NUMBER"CH5104KEB02"
ROOM"NIC1_P12V_MAM_MAM_BOM1"
PACK_TYPE"C0402"
VOLTAGE"25V"
VALUE"1UF"
LOCATION"PC2087"
ROOM1"NIC1_P12V_MAM_TIC_BOM2"
CDS_LIB"pure_quanta"
TOLERANCE"10%"
MATERIAL"EMPTY"
$SEC"1"
CDS_SEC"1";
"B"
$PN"2"59;
"A"
$PN"1"26;
%"Q_CAP"
"1","(6250,11000)","0","pure_quanta","I55";
;
PART_NUMBER"CH5104KEB02"
VALUE"1UF"
MATERIAL"EMPTY"
PACK_TYPE"C0402"
VOLTAGE"25V"
ROOM"NIC1_P12V_MAM_MAM_BOM1"
LOCATION"PC2085"
ROOM1"NIC1_P12V_MAM_TIC_BOM2"
CDS_LIB"pure_quanta"
TOLERANCE"10%"
$SEC"1"
CDS_SEC"1";
"B"
$PN"2"26;
"A"
$PN"1"60;
%"Q_RES"
"2","(6250,11425)","0","pure_quanta","I56";
;
PART_NUMBER"CS01002FB07"
ROOM"NIC1_P12V_MAM_MAM_BOM1"
PACK_TYPE"0402LF"
MATERIAL"EMPTY"
WATTAGE"1/16W"
VALUE"10"
TOLERANCE"1%"
LOCATION"PR3792"
ROOM1"NIC1_P12V_MAM_TIC_BOM2"
CDS_LIB"pure_quanta"
$SEC"1"
CDS_SEC"1";
"A"
$PN"1"6;
"B"
$PN"2"60;
%"GND"
"1","(6150,12025)","0","logical_power","I57";
;
HDL_POWER"GND"
SIZE"1B"
CDS_LIB"logical_power";
"A<SIZE-1..0>\NAC"27;
%"Q_RES"
"2","(6150,12275)","0","pure_quanta","I58";
;
PART_NUMBER"CS31502FB05"
ROOM"NIC1_P3V3_BOM1"
PACK_TYPE"0402LF"
MATERIAL"CHIP"
VALUE"15K"
TOLERANCE"1%"
WATTAGE"1/16W"
LOCATION"PR3791"
CDS_LIB"pure_quanta"
$SEC"1"
CDS_SEC"1";
"A"
$PN"1"57;
"B"
$PN"2"27;
%"GND"
"1","(7000,12000)","0","logical_power","I59";
;
CDS_LIB"logical_power"
HDL_POWER"GND"
SIZE"1B";
"A<SIZE-1..0>\NAC"28;
%"Q_RES"
"2","(7000,12300)","0","pure_quanta","I60";
;
PART_NUMBER"CS25362FB02"
ROOM"NIC1_P3V3_BOM1"
MATERIAL"CHIP"
PACK_TYPE"0402LF"
TOLERANCE"1%"
VALUE"5.36K"
WATTAGE"1/16W"
LOCATION"PR3780"
CDS_LIB"pure_quanta"
$SEC"1"
CDS_SEC"1";
"A"
$PN"1"56;
"B"
$PN"2"28;
%"MAX15090BEWIT"
"1","(7750,12800)","0","pure_quanta","I61";
;
PART_NUMBER"AL015080B00"
PART_TYPE"SMLF"
MATERIAL"IC"
ROOM"NIC1_P3V3_BOM1"
VALUE"MAX15090BEWI+T"
LOCATION"PU202"
CDS_LIB"pure_quanta"
PIN_NAMES_ROTATE"True"
CDS_LMAN_SYM_OUTLINE"-250,550,250,-550"
$SEC"1"
CDS_SEC"1";
"PG"
$PN"D7"45;
"FAULT# \B"
$PN"C7"44;
"GND_C2"
$PN"C2"32;
"GND_C1"
$PN"C1"32;
"GND_B2"
$PN"B2"32;
"CDLY"
$PN"A7"32;
"GATE"
$PN"A6"46;
"OUT_D6"
$PN"D6"13;
"OUT_D4"
$PN"D4"13;
"OUT_C6"
$PN"C6"13;
"OUT_C4"
$PN"C4"13;
"OUT_B6"
$PN"B6"13;
"OUT_B4"
$PN"B4"13;
"OUT_A4"
$PN"A4"13;
"ISENSE"
$PN"A1"47;
"OV"
$PN"D3"57;
"UV"
$PN"D2"37;
"REG"
$PN"D1"55;
"EN# \B"
$PN"B7"28;
"CB"
$PN"B1"56;
"IN_D5"
$PN"D5"9;
"IN_C5"
$PN"C5"9;
"IN_C3"
$PN"C3"9;
"IN_B5"
$PN"B5"9;
"IN_B3"
$PN"B3"9;
"IN_A5"
$PN"A5"9;
"IN_A3"
$PN"A3"9;
"VCC"
$PN"A2"38;
%"Q_RES"
"2","(4125,12500)","0","pure_quanta","I62";
;
PART_NUMBER"CS31002FB08"
VALUE"10K"
TOLERANCE"1%"
ROOM"NIC1_P3V3_BOM1"
PACK_TYPE"0402LF"
MATERIAL"CHIP"
WATTAGE"1/16W"
$LOCATION"R4070"
CDS_LIB"pure_quanta"
CDS_LOCATION"R4070"
$SEC"1"
CDS_SEC"1";
"A"
$PN"1"8;
"B"
$PN"2"64;
%"UNIVERSAL_POWER"
"1","(4125,12750)","0","logical_power","I63";
;
HDL_POWER"P12V_AUX"
CDS_LIB"logical_power";
"A"8;
%"Q_RES"
"1","(5550,12900)","0","pure_quanta","I64";
;
PART_NUMBER"CS00002JB13"
PACK_TYPE"0402LF"
VALUE"0"
WATTAGE"1/16W"
TOLERANCE"5%"
MATERIAL"CHIP"
ROOM"NIC1_P3V3_BOM1"
$LOCATION"R3785"
CDS_LIB"pure_quanta"
CDS_LOCATION"R3785"
$SEC"1"
CDS_SEC"1";
"B"
$PN"2"37;
"A"
$PN"1"58;
%"GND"
"1","(5800,13250)","0","logical_power","I65";
;
SIZE"1B"
HDL_POWER"GND"
CDS_LIB"logical_power";
"A<SIZE-1..0>\NAC"29;
%"Q_CAP"
"1","(5800,13525)","0","pure_quanta","I66";
;
PART_NUMBER"CH5104KEB02"
VALUE"1UF"
VOLTAGE"25V"
MATERIAL"X6S"
PACK_TYPE"C0402"
$LOCATION"PC5328"
CDS_LIB"pure_quanta"
TOLERANCE"10%"
CDS_LOCATION"PC5328"
$SEC"1"
CDS_SEC"1";
"B"
$PN"2"29;
"A"
$PN"1"9;
%"UNIVERSAL_POWER"
"1","(5800,13875)","0","logical_power","I67";
;
HDL_POWER"P3V3_AUX"
CDS_LIB"logical_power";
"A"9;
%"Q_RES"
"2","(6150,12550)","0","pure_quanta","I68";
;
PART_NUMBER"CS27152FB03"
ROOM"NIC1_P3V3_BOM1"
MATERIAL"CHIP"
WATTAGE"1/16W"
TOLERANCE"1%"
VALUE"7.15K"
PACK_TYPE"0402LF"
LOCATION"PR3790"
CDS_LIB"pure_quanta"
$SEC"1"
CDS_SEC"1";
"A"
$PN"1"37;
"B"
$PN"2"57;
%"GND"
"1","(6475,12725)","0","logical_power","I69";
;
CDS_LIB"logical_power"
SIZE"1B"
HDL_POWER"GND";
"A<SIZE-1..0>\NAC"30;
%"Q_RES"
"2","(3800,8825)","0","pure_quanta","I7";
;
PART_NUMBER"CS21002FB06"
WATTAGE"1/16W"
MATERIAL"CHIP"
TOLERANCE"1%"
VALUE"1K"
PACK_TYPE"0402LF"
LOCATION"R1906"
CDS_LIB"pure_quanta"
$SEC"1"
CDS_SEC"1";
"A"
$PN"1"1;
"B"
$PN"2"72;
%"Q_RES"
"2","(6150,13275)","0","pure_quanta","I70";
;
PART_NUMBER"CS32552FB06"
MATERIAL"CHIP"
TOLERANCE"1%"
VALUE"25.5K"
WATTAGE"1/16W"
ROOM"NIC1_P3V3_BOM1"
PACK_TYPE"0402LF"
LOCATION"PR3789"
CDS_LIB"pure_quanta"
$SEC"1"
CDS_SEC"1";
"A"
$PN"1"9;
"B"
$PN"2"37;
%"Q_CAP"
"1","(6475,13100)","0","pure_quanta","I71";
;
PART_NUMBER"CH5104KEB02"
PACK_TYPE"C0402"
VALUE"1UF"
MATERIAL"X6S"
VOLTAGE"25V"
ROOM"NIC1_P3V3_BOM1"
LOCATION"PC2086"
TOLERANCE"10%"
CDS_LIB"pure_quanta"
$SEC"1"
CDS_SEC"1";
"B"
$PN"2"30;
"A"
$PN"1"38;
%"Q_CAP"
"1","(6700,12800)","1","pure_quanta","I72";
;
PART_NUMBER"CH5104KEB02"
VALUE"1UF"
PACK_TYPE"C0402"
VOLTAGE"25V"
ROOM"NIC1_P3V3_BOM1"
LOCATION"PC2093"
TOLERANCE"10%"
CDS_LIB"pure_quanta"
MATERIAL"X6S"
$SEC"1"
CDS_SEC"1";
"B"
$PN"2"55;
"A"
$PN"1"30;
%"Q_RES"
"2","(6475,13525)","0","pure_quanta","I73";
;
PART_NUMBER"CS01002FB07"
WATTAGE"1/16W"
TOLERANCE"1%"
VALUE"10"
PACK_TYPE"0402LF"
MATERIAL"CHIP"
ROOM"NIC1_P3V3_BOM1"
LOCATION"PR3798"
CDS_LIB"pure_quanta"
$SEC"1"
CDS_SEC"1";
"A"
$PN"1"9;
"B"
$PN"2"38;
%"Q_RES"
"2","(8250,9300)","0","pure_quanta","I74";
;
PART_NUMBER"CS31002FB08"
TOLERANCE"1%"
WATTAGE"1/16W"
VALUE"10K"
MATERIAL"CHIP"
PACK_TYPE"0402LF"
$LOCATION"R1150"
CDS_LIB"pure_quanta"
CDS_LOCATION"R1150"
$SEC"1"
CDS_SEC"1";
"A"
$PN"1"7;
"B"
$PN"2"40;
%"Q_RES"
"2","(8600,9300)","0","pure_quanta","I76";
;
PART_NUMBER"CS31002FB08"
MATERIAL"CHIP"
WATTAGE"1/16W"
PACK_TYPE"0402LF"
TOLERANCE"1%"
VALUE"10K"
$LOCATION"R4762"
CDS_LIB"pure_quanta"
CDS_LOCATION"R4762"
$SEC"1"
CDS_SEC"1";
"A"
$PN"1"7;
"B"
$PN"2"41;
%"GND"
"1","(8250,10025)","0","logical_power","I79";
;
HDL_POWER"GND"
CDS_LIB"logical_power"
SIZE"1B";
"A<SIZE-1..0>\NAC"31;
%"UNIVERSAL_POWER"
"1","(3800,9125)","0","logical_power","I8";
;
HDL_POWER"P3V3_AUX"
CDS_LIB"logical_power";
"A"1;
%"Q_RES"
"2","(8375,10300)","0","pure_quanta","I80";
;
PART_NUMBER"CS18452FB01"
VALUE"845"
TOLERANCE"1%"
PACK_TYPE"0402LF"
ROOM"NIC1_P12V_MAM_MAM_BOM1"
MATERIAL"EMPTY"
WATTAGE"1/16W"
LOCATION"PR3781"
ROOM1"NIC1_P12V_MAM_TIC_BOM2"
CDS_LIB"pure_quanta"
$SEC"1"
CDS_SEC"1";
"A"
$PN"1"51;
"B"
$PN"2"31;
%"Q_CAP"
"1","(8300,11025)","0","pure_quanta","I81";
;
PART_NUMBER"CH31006KB18"
PACK_TYPE"C0402"
VALUE"0.01UF"
VOLTAGE"50V"
MATERIAL"EMPTY"
LOCATION"PC2088"
TOLERANCE"10%"
CDS_LIB"pure_quanta"
$SEC"1"
CDS_SEC"1";
"B"
$PN"2"52;
"A"
$PN"1"11;
%"Q_RES"
"1","(9025,10700)","0","pure_quanta","I82";
;
PART_NUMBER"CS00002JB13"
ROOM"NIC1_P12V_MAM_MAM_BOM1"
PACK_TYPE"0402LF"
TOLERANCE"5%"
VALUE"0"
MATERIAL"EMPTY"
WATTAGE"1/16W"
LOCATION"R3144"
ROOM1"NIC1_P12V_MAM_TIC_BOM2"
CDS_LIB"pure_quanta"
$SEC"1"
CDS_SEC"1";
"B"
$PN"2"50;
"A"
$PN"1"53;
%"Q_CAP"
"1","(8975,10800)","1","pure_quanta","I83";
;
PART_NUMBER"CH23906KB14"
ROOM"NIC1_P12V_MAM_MAM_BOM1"
VOLTAGE"50V"
VALUE"3900PF"
PACK_TYPE"C0402"
$LOCATION"PC4056"
ROOM1"NIC1_P12V_MAM_TIC_BOM2"
CDS_LIB"pure_quanta"
TOLERANCE"10%"
MATERIAL"EMPTY"
CDS_LOCATION"PC4056"
$SEC"1"
CDS_SEC"1";
"B"
$PN"2"33;
"A"
$PN"1"52;
%"Q_RES"
"2","(8625,11025)","0","pure_quanta","I84";
;
PART_NUMBER"CS61002FB02"
WATTAGE"1/16W"
ROOM"NIC1_P12V_MAM_MAM_BOM1"
VALUE"10M"
TOLERANCE"1%"
MATERIAL"EMPTY"
PACK_TYPE"0402LF"
LOCATION"PR4524"
ROOM1"NIC1_P12V_MAM_TIC_BOM2"
CDS_LIB"pure_quanta"
$SEC"1"
CDS_SEC"1";
"A"
$PN"1"11;
"B"
$PN"2"52;
%"GND"
"1","(8475,12125)","0","logical_power","I85";
;
CDS_LIB"logical_power"
HDL_POWER"GND"
SIZE"1B";
"A<SIZE-1..0>\NAC"32;
%"SCHOTTKY_AC"
"1","(8725,11675)","1","pure_quanta","I86";
;
PART_NUMBER"BC000340Z30"
MATERIAL"IC"
VALUE"B340A-13-F"
LOCATION"PD102"
PART_TYPE"SMLF"
NEEDS_NO_SIZE"TRUE"
CDS_LIB"pure_quanta"
CDS_LMAN_SYM_OUTLINE"-75,50,75,-50"
$SEC"1"
CDS_SEC"1";
"C"
$PN"C"11;
"A"
$PN"A"34;
%"Q_RES"
"1","(9275,10500)","0","pure_quanta","I87";
;
PART_NUMBER"CS00002JB13"
ROOM"NIC1_P12V_MAM_MAM_BOM1"
PACK_TYPE"0402LF"
TOLERANCE"5%"
VALUE"0"
MATERIAL"EMPTY"
WATTAGE"1/16W"
$LOCATION"R3869"
CDS_LIB"pure_quanta"
CDS_LOCATION"R3869"
$SEC"1"
CDS_SEC"1";
"B"
$PN"2"49;
"A"
$PN"1"51;
%"Q_RES"
"1","(9275,10375)","0","pure_quanta","I88";
;
PART_NUMBER"CS00002JB13"
PACK_TYPE"0402LF"
TOLERANCE"5%"
VALUE"0"
MATERIAL"EMPTY"
WATTAGE"1/16W"
ROOM1"NIC1_P12V_MAM_TIC_BOM2"
$LOCATION"R3870"
CDS_LIB"pure_quanta"
CDS_LOCATION"R3870"
$SEC"1"
CDS_SEC"1";
"B"
$PN"2"48;
"A"
$PN"1"51;
%"GND"
"1","(9100,10725)","0","logical_power","I89";
;
HDL_POWER"GND"
CDS_LIB"logical_power"
SIZE"1B";
"A<SIZE-1..0>\NAC"33;
%"MOSFET_NCH_DUAL"
"1","(3325,10250)","0","pure_quanta","I9";
;
PART_NUMBER"BAM138K0003"
VALUE"PJT138K"
PART_TYPE"SMLF"
ROOM"NIC1_P12V_MAM_MAM_BOM1"
MATERIAL"EMPTY"
$LOCATION"Q123"
ROOM1"NIC1_P12V_MAM_TIC_BOM2"
NEEDS_NO_SIZE"TRUE"
CDS_LMAN_SYM_OUTLINE"-150,150,150,-150"
CDS_LIB"pure_quanta"
CDS_LOCATION"Q123"
$SEC"1"
CDS_SEC"1";
"D1"
$PN"6"69;
"G1"
$PN"2"73;
"S1"
$PN"1"16;
%"Q_RES"
"2","(9375,10975)","0","pure_quanta","I90";
;
PART_NUMBER"CS41002FB09"
PACK_TYPE"0402LF"
MATERIAL"EMPTY"
WATTAGE"1/16W"
ROOM"NIC1_P12V_MAM_MAM_BOM1"
VALUE"100K"
TOLERANCE"1%"
LOCATION"R3799"
ROOM1"NIC1_P12V_MAM_TIC_BOM2"
CDS_LIB"pure_quanta"
$SEC"1"
CDS_SEC"1";
"A"
$PN"1"10;
"B"
$PN"2"54;
%"VCCAUX15"
"1","(9550,11275)","0","logical_power","I91";
;
HDL_POWER"P3V3_AUX"
CDS_LIB"logical_power";
"A"10;
%"Q_RES"
"2","(9800,10975)","0","pure_quanta","I92";
;
PART_NUMBER"CS41002FB09"
VALUE"100K"
ROOM"NIC1_P12V_MAM_MAM_BOM1"
TOLERANCE"1%"
MATERIAL"EMPTY"
WATTAGE"1/16W"
PACK_TYPE"0402LF"
LOCATION"R3797"
ROOM1"NIC1_P12V_MAM_TIC_BOM2"
CDS_LIB"pure_quanta"
$SEC"1"
CDS_SEC"1";
"A"
$PN"1"10;
"B"
$PN"2"50;
%"Q_CAP"
"1","(9200,11650)","0","pure_quanta","I93";
;
PART_NUMBER"CH4104K1B00"
PACK_TYPE"0402"
MATERIAL"X7R"
VOLTAGE"25V"
VALUE"0.1UF"
LOCATION"PC2092"
TOLERANCE"10%"
CDS_LIB"pure_quanta"
$SEC"1"
CDS_SEC"1";
"B"
$PN"2"34;
"A"
$PN"1"11;
%"Q_CAP"
"1","(9625,11650)","0","pure_quanta","I94";
;
PART_NUMBER"CH6223MEA03"
MATERIAL"X6S"
PACK_TYPE"C0805"
VALUE"22UF"
VOLTAGE"16V"
LOCATION"PC2080"
TOLERANCE"20%"
CDS_LIB"pure_quanta"
$SEC"1"
CDS_SEC"1";
"B"
$PN"2"34;
"A"
$PN"1"11;
%"GND"
"1","(10025,11300)","0","logical_power","I95";
;
HDL_POWER"GND"
SIZE"1B"
CDS_LIB"logical_power";
"A<SIZE-1..0>\NAC"34;
%"Q_CAP"
"1","(10025,11650)","0","pure_quanta","I96";
;
PART_NUMBER"CH6103KEA03"
PACK_TYPE"C0805"
MATERIAL"X6S"
VOLTAGE"16V"
VALUE"10UF"
LOCATION"PC2082"
TOLERANCE"10%"
CDS_LIB"pure_quanta"
$SEC"1"
CDS_SEC"1";
"B"
$PN"2"34;
"A"
$PN"1"11;
%"UNIVERSAL_POWER"
"1","(10025,11950)","2","logical_power","I97";
;
HDL_POWER"P12V_OCP_SFF"
CDS_LIB"logical_power";
"A"11;
END.
